(kicad_pcb
	(version 20241229)
	(generator "pcbnew")
	(generator_version "9.0")
	(general
		(thickness 1.6)
		(legacy_teardrops no)
	)
	(paper "A4")
	(title_block
		(title "OCuLink to PCIe adapter")
		(date "2025-06-18")
		(rev "1.0.0")
		(company "Antmicro Ltd")
		(comment 1 "www.antmicro.com")
		(comment 9 "footprints 146-149 of 159")
	)
	(layers
		(0 "F.Cu" signal)
		(4 "In1.Cu" signal)
		(6 "In2.Cu" signal)
		(2 "B.Cu" signal)
		(9 "F.Adhes" user "F.Adhesive")
		(11 "B.Adhes" user "B.Adhesive")
		(13 "F.Paste" user)
		(15 "B.Paste" user)
		(5 "F.SilkS" user "F.Silkscreen")
		(7 "B.SilkS" user "B.Silkscreen")
		(1 "F.Mask" user)
		(3 "B.Mask" user)
		(17 "Dwgs.User" user "User.Drawings")
		(19 "Cmts.User" user "User.Comments")
		(21 "Eco1.User" user "User.Eco1")
		(23 "Eco2.User" user "User.Eco2")
		(25 "Edge.Cuts" user)
		(27 "Margin" user)
		(31 "F.CrtYd" user "F.Courtyard")
		(29 "B.CrtYd" user "B.Courtyard")
		(35 "F.Fab" user)
		(33 "B.Fab" user)
	)
	(footprint "antmicro-footprints:C_0402_1005Metric"
		(layer "F.Cu")
		(at 141 146.75 180)
		(descr "Capacitor SMD 0402")
		(tags "capacitor SMD 0402")
		(property "Reference" "C14"
			(at -1 -0.65 180)
			(layer "F.SilkS")
			(effects
				(font
					(size 0.7 0.7)
					(thickness 0.15)
				)
				(justify right top)
			)
		)
		(property "Value" "C_1u_25V_0402"
			(at -1.022927 2.155213 0)
			(layer "F.Fab")
			(effects
				(font
					(size 0.7 0.7)
					(thickness 0.15)
				)
				(justify right top)
			)
		)
		(property "Datasheet" "https://www.murata.com/products/productdetail?partno=GRM155R61E105KE11%23"
			(at 0 0 0)
			(layer "F.Fab")
			(hide yes)
			(effects
				(font
					(size 1.27 1.27)
					(thickness 0.15)
				)
			)
		)
		(property "Description" "SMD Multilayer Ceramic Capacitor, 1 µF, 25 V, 0402 [1005 Metric], ± 10%, X5R, GRM Series"
			(at 0 0 0)
			(layer "F.Fab")
			(hide yes)
			(effects
				(font
					(size 1.27 1.27)
					(thickness 0.15)
				)
			)
		)
		(property "MPN" "GRM155R61E105KE11J"
			(at 0 0 180)
			(unlocked yes)
			(layer "F.Fab")
			(hide yes)
			(effects
				(font
					(size 1 1)
					(thickness 0.15)
				)
			)
		)
		(property "Manufacturer" "Murata"
			(at 0 0 180)
			(unlocked yes)
			(layer "F.Fab")
			(hide yes)
			(effects
				(font
					(size 1 1)
					(thickness 0.15)
				)
			)
		)
		(property "License" "Apache-2.0"
			(at 0 0 180)
			(unlocked yes)
			(layer "F.Fab")
			(hide yes)
			(effects
				(font
					(size 1 1)
					(thickness 0.15)
				)
			)
		)
		(property "Author" "Antmicro"
			(at 0 0 180)
			(unlocked yes)
			(layer "F.Fab")
			(hide yes)
			(effects
				(font
					(size 1 1)
					(thickness 0.15)
				)
			)
		)
		(property "Val" "1u"
			(at 0 0 180)
			(unlocked yes)
			(layer "F.Fab")
			(hide yes)
			(effects
				(font
					(size 1 1)
					(thickness 0.15)
				)
			)
		)
		(property "Voltage" "25V"
			(at 0 0 180)
			(unlocked yes)
			(layer "F.Fab")
			(hide yes)
			(effects
				(font
					(size 1 1)
					(thickness 0.15)
				)
			)
		)
		(property "Dielectric" "X5R"
			(at 0 0 180)
			(unlocked yes)
			(layer "F.Fab")
			(hide yes)
			(effects
				(font
					(size 1 1)
					(thickness 0.15)
				)
			)
		)
		(sheetname "/Power/Ideal-diode-2/")
		(sheetfile "ideal-diode.kicad_sch")
		(attr smd)
		(fp_rect
			(start -0.925 -0.47)
			(end 0.925 0.47)
			(stroke
				(width 0.05)
				(type default)
			)
			(fill no)
			(layer "F.CrtYd")
		)
		(fp_line
			(start 0.504 0.248)
			(end -0.494 0.248)
			(stroke
				(width 0.15)
				(type solid)
			)
			(layer "F.Fab")
		)
		(fp_line
			(start 0.504 -0.25)
			(end 0.504 0.248)
			(stroke
				(width 0.15)
				(type solid)
			)
			(layer "F.Fab")
		)
		(fp_line
			(start -0.494 0.248)
			(end -0.494 -0.25)
			(stroke
				(width 0.15)
				(type solid)
			)
			(layer "F.Fab")
		)
		(fp_line
			(start -0.494 -0.25)
			(end 0.504 -0.25)
			(stroke
				(width 0.15)
				(type solid)
			)
			(layer "F.Fab")
		)
		(fp_text user "${REFERENCE}"
			(at 0 0 0)
			(layer "F.Fab")
			(effects
				(font
					(size 0.7 0.7)
					(thickness 0.15)
				)
				(justify right top)
			)
		)
		(fp_text user "Author: Antmicro"
			(at -0.939 3.399 0)
			(layer "F.Fab")
			(effects
				(font
					(size 0.7 0.7)
					(thickness 0.15)
				)
				(justify right top)
			)
		)
		(fp_text user "License: Apache-2.0"
			(at -0.939 5.799 0)
			(layer "F.Fab")
			(effects
				(font
					(size 0.7 0.7)
					(thickness 0.15)
				)
				(justify right top)
			)
		)
		(pad "1" smd roundrect
			(at -0.48 0 180)
			(size 0.59 0.64)
			(layers "F.Cu" "F.Mask" "F.Paste")
			(roundrect_rratio 0.25)
			(net 66 "GND")
			(pintype "passive")
		)
		(pad "2" smd roundrect
			(at 0.48 0 180)
			(size 0.59 0.64)
			(layers "F.Cu" "F.Mask" "F.Paste")
			(roundrect_rratio 0.25)
			(net 87 "+12V")
			(pintype "passive")
		)
	)
	(footprint "antmicro-footprints:USON-10_2.5x1mm_P0.5mm"
		(layer "F.Cu")
		(at 127.298 43.387 -90)
		(descr "USON-10 2.5x1mm_ Pitch 0.5mm")
		(tags "USON-10 2.5x1mm Pitch 0.5mm")
		(property "Reference" "D14"
			(at 1.113 -0.452 180)
			(layer "F.SilkS")
			(effects
				(font
					(size 0.7 0.7)
					(thickness 0.15)
				)
				(justify right top)
			)
		)
		(property "Value" "ESD204DQAR"
			(at 0.018 2.499 90)
			(layer "F.Fab")
			(effects
				(font
					(size 0.7 0.7)
					(thickness 0.15)
				)
				(justify right top)
			)
		)
		(property "Datasheet" "https://www.ti.com/lit/ds/symlink/esd204.pdf?ts=1706004844383&ref_url=https%253A%252F%252Fwww.ti.com%252Finterface%252Fdiodes%252Fesd-protection-diodes%252Fproducts.html"
			(at 0 0 90)
			(layer "F.Fab")
			(hide yes)
			(effects
				(font
					(size 1.27 1.27)
					(thickness 0.15)
				)
			)
		)
		(property "Description" "TVS diode array, 30 kV, USON-10, 3.6 V, 0.55 pF"
			(at 0 0 90)
			(layer "F.Fab")
			(hide yes)
			(effects
				(font
					(size 1.27 1.27)
					(thickness 0.15)
				)
			)
		)
		(property "MPN" "ESD204DQAR"
			(at 0 0 270)
			(unlocked yes)
			(layer "F.Fab")
			(hide yes)
			(effects
				(font
					(size 1 1)
					(thickness 0.15)
				)
			)
		)
		(property "Manufacturer" "Texas Instruments"
			(at 0 0 270)
			(unlocked yes)
			(layer "F.Fab")
			(hide yes)
			(effects
				(font
					(size 1 1)
					(thickness 0.15)
				)
			)
		)
		(property "Author" "Antmicro"
			(at 0 0 270)
			(unlocked yes)
			(layer "F.Fab")
			(hide yes)
			(effects
				(font
					(size 1 1)
					(thickness 0.15)
				)
			)
		)
		(property "License" "Apache-2.0"
			(at 0 0 270)
			(unlocked yes)
			(layer "F.Fab")
			(hide yes)
			(effects
				(font
					(size 1 1)
					(thickness 0.15)
				)
			)
		)
		(sheetname "/OCuLink/")
		(sheetfile "oculink.kicad_sch")
		(attr smd)
		(fp_line
			(start 0.498 1.398)
			(end -0.5 1.398)
			(stroke
				(width 0.15)
				(type solid)
			)
			(layer "F.SilkS")
		)
		(fp_line
			(start 0.498 -1.401)
			(end -0.5 -1.401)
			(stroke
				(width 0.15)
				(type solid)
			)
			(layer "F.SilkS")
		)
		(fp_circle
			(center -0.68 -1.27)
			(end -0.63 -1.27)
			(stroke
				(width 0.15)
				(type solid)
			)
			(fill yes)
			(layer "F.SilkS")
		)
		(fp_rect
			(start -0.8 -1.5)
			(end 0.8 1.499)
			(stroke
				(width 0.05)
				(type solid)
			)
			(fill no)
			(layer "F.CrtYd")
		)
		(fp_line
			(start -0.5 1.249)
			(end 0.498 1.249)
			(stroke
				(width 0.15)
				(type solid)
			)
			(layer "F.Fab")
		)
		(fp_line
			(start -0.5 -1)
			(end -0.5 1.249)
			(stroke
				(width 0.15)
				(type solid)
			)
			(layer "F.Fab")
		)
		(fp_line
			(start -0.25 -1.25)
			(end -0.5 -1)
			(stroke
				(width 0.15)
				(type solid)
			)
			(layer "F.Fab")
		)
		(fp_line
			(start 0.498 -1.25)
			(end 0.498 1.249)
			(stroke
				(width 0.15)
				(type solid)
			)
			(layer "F.Fab")
		)
		(fp_line
			(start 0.498 -1.25)
			(end -0.25 -1.25)
			(stroke
				(width 0.15)
				(type solid)
			)
			(layer "F.Fab")
		)
		(fp_text user "${REFERENCE}"
			(at 0 -0.000501 90)
			(layer "F.Fab")
			(effects
				(font
					(size 0.7 0.7)
					(thickness 0.15)
				)
				(justify right top)
			)
		)
		(fp_text user "Author: Antmicro"
			(at -0.802 5.7 90)
			(layer "F.Fab")
			(effects
				(font
					(size 0.7 0.7)
					(thickness 0.15)
				)
				(justify right top)
			)
		)
		(fp_text user "License: Apache-2.0"
			(at -0.802 6.9 90)
			(layer "F.Fab")
			(effects
				(font
					(size 0.7 0.7)
					(thickness 0.15)
				)
				(justify right top)
			)
		)
		(pad "1" smd roundrect
			(at -0.387 -1 180)
			(size 0.25 0.55)
			(layers "F.Cu" "F.Mask" "F.Paste")
			(roundrect_rratio 0.25)
			(net 132 "unconnected-(D14-Pad1)")
			(pintype "passive+no_connect")
		)
		(pad "2" smd roundrect
			(at -0.387 -0.5 180)
			(size 0.25 0.55)
			(layers "F.Cu" "F.Mask" "F.Paste")
			(roundrect_rratio 0.25)
			(net 184 "/OCuLink/~{WAKEC}")
			(pintype "passive")
		)
		(pad "3" smd roundrect
			(at -0.387 0 180)
			(size 0.4 0.55)
			(layers "F.Cu" "F.Mask" "F.Paste")
			(roundrect_rratio 0.25)
			(net 66 "GND")
			(pintype "power_in")
		)
		(pad "4" smd roundrect
			(at -0.387 0.498 180)
			(size 0.25 0.55)
			(layers "F.Cu" "F.Mask" "F.Paste")
			(roundrect_rratio 0.25)
			(net 170 "/OCuLink/PCIe_{REF0}_R.CK+")
			(pintype "passive")
		)
		(pad "5" smd roundrect
			(at -0.387 0.998 180)
			(size 0.25 0.55)
			(layers "F.Cu" "F.Mask" "F.Paste")
			(roundrect_rratio 0.25)
			(net 171 "/OCuLink/PCIe_{REF0}_R.CK-")
			(pintype "passive")
		)
		(pad "6" smd roundrect
			(at 0.385 0.998 180)
			(size 0.25 0.55)
			(layers "F.Cu" "F.Mask" "F.Paste")
			(roundrect_rratio 0.25)
			(net 171 "/OCuLink/PCIe_{REF0}_R.CK-")
			(pintype "passive")
		)
		(pad "7" smd roundrect
			(at 0.385 0.498 180)
			(size 0.25 0.55)
			(layers "F.Cu" "F.Mask" "F.Paste")
			(roundrect_rratio 0.25)
			(net 170 "/OCuLink/PCIe_{REF0}_R.CK+")
			(pintype "passive")
		)
		(pad "8" smd roundrect
			(at 0.385 0 180)
			(size 0.4 0.55)
			(layers "F.Cu" "F.Mask" "F.Paste")
			(roundrect_rratio 0.25)
			(net 66 "GND")
			(pintype "passive")
		)
		(pad "9" smd roundrect
			(at 0.385 -0.5 180)
			(size 0.25 0.55)
			(layers "F.Cu" "F.Mask" "F.Paste")
			(roundrect_rratio 0.25)
			(net 184 "/OCuLink/~{WAKEC}")
			(pintype "passive")
		)
		(pad "10" smd roundrect
			(at 0.385 -1 180)
			(size 0.25 0.55)
			(layers "F.Cu" "F.Mask" "F.Paste")
			(roundrect_rratio 0.25)
			(net 188 "unconnected-(D14-Pad1)_1")
			(pintype "passive+no_connect")
		)
	)
	(footprint "antmicro-footprints:C_0402_1005Metric"
		(layer "F.Cu")
		(at 127.1 134.4)
		(descr "Capacitor SMD 0402")
		(tags "capacitor SMD 0402")
		(property "Reference" "C1"
			(at 2.5 -0.4 180)
			(layer "F.SilkS")
			(effects
				(font
					(size 0.7 0.7)
					(thickness 0.15)
				)
				(justify left bottom)
			)
		)
		(property "Value" "C_100n_0402"
			(at -1.022927 2.155213 0)
			(layer "F.Fab")
			(effects
				(font
					(size 0.7 0.7)
					(thickness 0.15)
				)
				(justify left bottom)
			)
		)
		(property "Datasheet" "https://www.murata.com/products/productdetail?partno=GRM155R61H104KE14%23"
			(at 0 0 0)
			(layer "F.Fab")
			(hide yes)
			(effects
				(font
					(size 1.27 1.27)
					(thickness 0.15)
				)
			)
		)
		(property "Description" "SMD Multilayer Ceramic Capacitor, 0.1 µF, 50 V, 0402 [1005 Metric], ± 10%, X5R, GRM Series"
			(at 0 0 0)
			(layer "F.Fab")
			(hide yes)
			(effects
				(font
					(size 1.27 1.27)
					(thickness 0.15)
				)
			)
		)
		(property "MPN" "GRM155R61H104KE14D"
			(at 0 0 0)
			(unlocked yes)
			(layer "F.Fab")
			(hide yes)
			(effects
				(font
					(size 1 1)
					(thickness 0.15)
				)
			)
		)
		(property "Manufacturer" "Murata"
			(at 0 0 0)
			(unlocked yes)
			(layer "F.Fab")
			(hide yes)
			(effects
				(font
					(size 1 1)
					(thickness 0.15)
				)
			)
		)
		(property "License" "Apache-2.0"
			(at 0 0 0)
			(unlocked yes)
			(layer "F.Fab")
			(hide yes)
			(effects
				(font
					(size 1 1)
					(thickness 0.15)
				)
			)
		)
		(property "Author" "Antmicro"
			(at 0 0 0)
			(unlocked yes)
			(layer "F.Fab")
			(hide yes)
			(effects
				(font
					(size 1 1)
					(thickness 0.15)
				)
			)
		)
		(property "Val" "100n"
			(at 0 0 0)
			(unlocked yes)
			(layer "F.Fab")
			(hide yes)
			(effects
				(font
					(size 1 1)
					(thickness 0.15)
				)
			)
		)
		(property "Voltage" "50V"
			(at 0 0 0)
			(unlocked yes)
			(layer "F.Fab")
			(hide yes)
			(effects
				(font
					(size 1 1)
					(thickness 0.15)
				)
			)
		)
		(property "Dielectric" "X5R"
			(at 0 0 0)
			(unlocked yes)
			(layer "F.Fab")
			(hide yes)
			(effects
				(font
					(size 1 1)
					(thickness 0.15)
				)
			)
		)
		(sheetname "/Power/")
		(sheetfile "power.kicad_sch")
		(attr smd)
		(fp_rect
			(start -0.925 -0.47)
			(end 0.925 0.47)
			(stroke
				(width 0.05)
				(type default)
			)
			(fill no)
			(layer "F.CrtYd")
		)
		(fp_line
			(start -0.494 -0.25)
			(end 0.504 -0.25)
			(stroke
				(width 0.15)
				(type solid)
			)
			(layer "F.Fab")
		)
		(fp_line
			(start -0.494 0.248)
			(end -0.494 -0.25)
			(stroke
				(width 0.15)
				(type solid)
			)
			(layer "F.Fab")
		)
		(fp_line
			(start 0.504 -0.25)
			(end 0.504 0.248)
			(stroke
				(width 0.15)
				(type solid)
			)
			(layer "F.Fab")
		)
		(fp_line
			(start 0.504 0.248)
			(end -0.494 0.248)
			(stroke
				(width 0.15)
				(type solid)
			)
			(layer "F.Fab")
		)
		(fp_text user "${REFERENCE}"
			(at 0 0 0)
			(layer "F.Fab")
			(effects
				(font
					(size 0.7 0.7)
					(thickness 0.15)
				)
				(justify left bottom)
			)
		)
		(fp_text user "Author: Antmicro"
			(at -0.939 3.399 0)
			(layer "F.Fab")
			(effects
				(font
					(size 0.7 0.7)
					(thickness 0.15)
				)
				(justify left bottom)
			)
		)
		(fp_text user "License: Apache-2.0"
			(at -0.939 5.799 0)
			(layer "F.Fab")
			(effects
				(font
					(size 0.7 0.7)
					(thickness 0.15)
				)
				(justify left bottom)
			)
		)
		(pad "1" smd roundrect
			(at -0.48 0)
			(size 0.59 0.64)
			(layers "F.Cu" "F.Mask" "F.Paste")
			(roundrect_rratio 0.25)
			(net 85 "/Power/3V3_BST")
			(pintype "passive")
		)
		(pad "2" smd roundrect
			(at 0.48 0)
			(size 0.59 0.64)
			(layers "F.Cu" "F.Mask" "F.Paste")
			(roundrect_rratio 0.25)
			(net 86 "/Power/3V3_SW")
			(pintype "passive")
		)
	)
	(footprint "antmicro-footprints:C_0402_1005Metric"
		(layer "F.Cu")
		(at 146.562 54.001)
		(descr "Capacitor SMD 0402")
		(tags "capacitor SMD 0402")
		(property "Reference" "C40"
			(at -3.162 2.999 180)
			(layer "F.SilkS")
			(effects
				(font
					(size 0.7 0.7)
					(thickness 0.15)
				)
				(justify left bottom)
			)
		)
		(property "Value" "C_100n_0402"
			(at -1.022927 2.155213 0)
			(layer "F.Fab")
			(effects
				(font
					(size 0.7 0.7)
					(thickness 0.15)
				)
				(justify left bottom)
			)
		)
		(property "Datasheet" "https://www.murata.com/products/productdetail?partno=GRM155R61H104KE14%23"
			(at 0 0 0)
			(layer "F.Fab")
			(hide yes)
			(effects
				(font
					(size 1.27 1.27)
					(thickness 0.15)
				)
			)
		)
		(property "Description" "SMD Multilayer Ceramic Capacitor, 0.1 µF, 50 V, 0402 [1005 Metric], ± 10%, X5R, GRM Series"
			(at 0 0 0)
			(layer "F.Fab")
			(hide yes)
			(effects
				(font
					(size 1.27 1.27)
					(thickness 0.15)
				)
			)
		)
		(property "MPN" "GRM155R61H104KE14D"
			(at 0 0 0)
			(unlocked yes)
			(layer "F.Fab")
			(hide yes)
			(effects
				(font
					(size 1 1)
					(thickness 0.15)
				)
			)
		)
		(property "Manufacturer" "Murata"
			(at 0 0 0)
			(unlocked yes)
			(layer "F.Fab")
			(hide yes)
			(effects
				(font
					(size 1 1)
					(thickness 0.15)
				)
			)
		)
		(property "License" "Apache-2.0"
			(at 0 0 0)
			(unlocked yes)
			(layer "F.Fab")
			(hide yes)
			(effects
				(font
					(size 1 1)
					(thickness 0.15)
				)
			)
		)
		(property "Author" "Antmicro"
			(at 0 0 0)
			(unlocked yes)
			(layer "F.Fab")
			(hide yes)
			(effects
				(font
					(size 1 1)
					(thickness 0.15)
				)
			)
		)
		(property "Val" "100n"
			(at 0 0 0)
			(unlocked yes)
			(layer "F.Fab")
			(hide yes)
			(effects
				(font
					(size 1 1)
					(thickness 0.15)
				)
			)
		)
		(property "Voltage" "50V"
			(at 0 0 0)
			(unlocked yes)
			(layer "F.Fab")
			(hide yes)
			(effects
				(font
					(size 1 1)
					(thickness 0.15)
				)
			)
		)
		(property "Dielectric" "X5R"
			(at 0 0 0)
			(unlocked yes)
			(layer "F.Fab")
			(hide yes)
			(effects
				(font
					(size 1 1)
					(thickness 0.15)
				)
			)
		)
		(sheetname "/USB-PD/")
		(sheetfile "usb-pd.kicad_sch")
		(attr smd)
		(fp_rect
			(start -0.925 -0.47)
			(end 0.925 0.47)
			(stroke
				(width 0.05)
				(type default)
			)
			(fill no)
			(layer "F.CrtYd")
		)
		(fp_line
			(start -0.494 -0.25)
			(end 0.504 -0.25)
			(stroke
				(width 0.15)
				(type solid)
			)
			(layer "F.Fab")
		)
		(fp_line
			(start -0.494 0.248)
			(end -0.494 -0.25)
			(stroke
				(width 0.15)
				(type solid)
			)
			(layer "F.Fab")
		)
		(fp_line
			(start 0.504 -0.25)
			(end 0.504 0.248)
			(stroke
				(width 0.15)
				(type solid)
			)
			(layer "F.Fab")
		)
		(fp_line
			(start 0.504 0.248)
			(end -0.494 0.248)
			(stroke
				(width 0.15)
				(type solid)
			)
			(layer "F.Fab")
		)
		(fp_text user "License: Apache-2.0"
			(at -0.939 5.799 0)
			(layer "F.Fab")
			(effects
				(font
					(size 0.7 0.7)
					(thickness 0.15)
				)
				(justify left bottom)
			)
		)
		(fp_text user "Author: Antmicro"
			(at -0.939 3.399 0)
			(layer "F.Fab")
			(effects
				(font
					(size 0.7 0.7)
					(thickness 0.15)
				)
				(justify left bottom)
			)
		)
		(fp_text user "${REFERENCE}"
			(at 0 0 0)
			(layer "F.Fab")
			(effects
				(font
					(size 0.7 0.7)
					(thickness 0.15)
				)
				(justify left bottom)
			)
		)
		(pad "1" smd roundrect
			(at -0.48 0)
			(size 0.59 0.64)
			(layers "F.Cu" "F.Mask" "F.Paste")
			(roundrect_rratio 0.25)
			(net 66 "GND")
			(pintype "passive")
		)
		(pad "2" smd roundrect
			(at 0.48 0)
			(size 0.59 0.64)
			(layers "F.Cu" "F.Mask" "F.Paste")
			(roundrect_rratio 0.25)
			(net 117 "/USB-PD/VDDD_3V3")
			(pintype "passive")
		)
	)
)
